(kicad_pcb
	(version 20260206)
	(generator "pcbnew")
	(generator_version "10.0")
	(general
		(thickness 1.6)
		(legacy_teardrops no)
	)
	(paper "A4")
	(title_block
		(title "baseboard — 13948-1b.1110WZS1818.brd")
		(comment 1 "Honey Badger (Wiwynn) / footprints 1378-1382 of 2523")
	)
	(layers
		(0 "F.Cu" signal "TOP")
		(4 "In1.Cu" signal "L2GND")
		(6 "In2.Cu" signal "L3")
		(8 "In3.Cu" signal "L4VCC")
		(10 "In4.Cu" signal "L5VCC")
		(12 "In5.Cu" signal "L6")
		(14 "In6.Cu" signal "L7GND")
		(2 "B.Cu" signal "BOTTOM")
		(9 "F.Adhes" user "F.Adhesive")
		(11 "B.Adhes" user "B.Adhesive")
		(13 "F.Paste" user "Package Geometry/Pastemask Top")
		(15 "B.Paste" user "Package Geometry/Pastemask Bottom")
		(5 "F.SilkS" user "Ref Des/Silkscreen Top")
		(7 "B.SilkS" user "Ref Des/Silkscreen Bottom")
		(1 "F.Mask" user "Board Geometry/Soldermask Top")
		(3 "B.Mask" user "Board Geometry/Soldermask Bottom")
		(17 "Dwgs.User" user "User.Drawings")
		(19 "Cmts.User" user "User.Comments")
		(21 "Eco1.User" user "User.Eco1")
		(23 "Eco2.User" user "User.Eco2")
		(25 "Edge.Cuts" user "Board Geometry/Outline")
		(27 "Margin" user)
		(31 "F.CrtYd" user "Package Geometry/Place Bound Top")
		(29 "B.CrtYd" user "Package Geometry/Place Bound Bottom")
		(35 "F.Fab" user "Ref Des/Assembly Top")
		(33 "B.Fab" user "Ref Des/Assembly Bottom")
	)
	(footprint ""
		(layer "F.Cu")
		(at 43.75023 -132.2705 -90)
		(property "Reference" "SQ13"
			(at 0 0 270)
			(layer "F.SilkS")
			(hide yes)
			(effects
				(font
					(size 1.27 1.27)
				)
			)
		)
		(property "Value" "2N7002A-7-GP"
			(at 0.127 -8.9662 270)
			(unlocked yes)
			(layer "F.Fab")
			(hide yes)
			(effects
				(font
					(size 1.016 1.016)
					(thickness 0.1524)
				)
			)
		)
		(property "Device Type" "SOT23DGS2D4H48"
			(at 0.127 -10.4902 270)
			(unlocked yes)
			(layer "F.Fab")
			(hide yes)
			(effects
				(font
					(size 1.016 1.016)
					(thickness 0.1524)
				)
			)
		)
		(duplicate_pad_numbers_are_jumpers no)
		(fp_line
			(start -1.651 1.778)
			(end 1.651 1.778)
			(stroke
				(width 0.1524)
				(type default)
			)
			(layer "F.SilkS")
		)
		(fp_line
			(start 1.651 1.778)
			(end 1.651 -1.778)
			(stroke
				(width 0.1524)
				(type default)
			)
			(layer "F.SilkS")
		)
		(fp_line
			(start -1.651 -1.778)
			(end -1.651 1.778)
			(stroke
				(width 0.1524)
				(type default)
			)
			(layer "F.SilkS")
		)
		(fp_line
			(start 1.651 -1.778)
			(end -1.651 -1.778)
			(stroke
				(width 0.1524)
				(type default)
			)
			(layer "F.SilkS")
		)
		(fp_poly
			(pts
				(xy -1.778 1.8796) (xy -1.778 -1.8796) (xy 1.778 -1.8796) (xy 1.778 1.8796)
			)
			(stroke
				(width 0)
				(type default)
			)
			(fill no)
			(layer "F.CrtYd")
		)
		(fp_poly
			(pts
				(xy -1.778 1.8796) (xy -1.778 -1.8796) (xy 1.778 -1.8796) (xy 1.778 1.8796)
			)
			(stroke
				(width 0)
				(type default)
			)
			(fill no)
			(layer "F.Fab")
		)
		(pad "D" smd custom
			(at 0 -0.9525 270)
			(size 0.1905 0.1905)
			(layers "F.Cu" "F.Mask" "F.Paste")
			(net "EXP_RST_R")
			(options
				(clearance outline)
				(anchor circle)
			)
			(primitives
				(gr_poly
					(pts
						(arc
							(start -0.1778 0.5715)
							(mid -0.321484 0.511984)
							(end -0.381 0.3683)
						)
						(arc
							(start -0.381 -0.3683)
							(mid -0.321484 -0.511984)
							(end -0.1778 -0.5715)
						)
						(arc
							(start 0.1778 -0.5715)
							(mid 0.321484 -0.511984)
							(end 0.381 -0.3683)
						)
						(arc
							(start 0.381 0.3683)
							(mid 0.321484 0.511984)
							(end 0.1778 0.5715)
						)
					)
					(width 0)
					(fill yes)
				)
			)
		)
		(pad "G" smd custom
			(at -0.98425 0.9525 270)
			(size 0.1905 0.1905)
			(layers "F.Cu" "F.Mask" "F.Paste")
			(net "P3V3_STBY_G5")
			(options
				(clearance outline)
				(anchor circle)
			)
			(primitives
				(gr_poly
					(pts
						(arc
							(start -0.1778 0.5715)
							(mid -0.321484 0.511984)
							(end -0.381 0.3683)
						)
						(arc
							(start -0.381 -0.3683)
							(mid -0.321484 -0.511984)
							(end -0.1778 -0.5715)
						)
						(arc
							(start 0.1778 -0.5715)
							(mid 0.321484 -0.511984)
							(end 0.381 -0.3683)
						)
						(arc
							(start 0.381 0.3683)
							(mid 0.321484 0.511984)
							(end 0.1778 0.5715)
						)
					)
					(width 0)
					(fill yes)
				)
			)
		)
		(pad "S" smd custom
			(at 0.98425 0.9525 270)
			(size 0.1905 0.1905)
			(layers "F.Cu" "F.Mask" "F.Paste")
			(net "GND")
			(options
				(clearance outline)
				(anchor circle)
			)
			(primitives
				(gr_poly
					(pts
						(arc
							(start -0.1778 0.5715)
							(mid -0.321484 0.511984)
							(end -0.381 0.3683)
						)
						(arc
							(start -0.381 -0.3683)
							(mid -0.321484 -0.511984)
							(end -0.1778 -0.5715)
						)
						(arc
							(start 0.1778 -0.5715)
							(mid 0.321484 -0.511984)
							(end 0.381 -0.3683)
						)
						(arc
							(start 0.381 0.3683)
							(mid 0.321484 0.511984)
							(end 0.1778 0.5715)
						)
					)
					(width 0)
					(fill yes)
				)
			)
		)
	)
	(footprint ""
		(layer "F.Cu")
		(at 202.565 -138.811 -90)
		(property "Reference" "SR758"
			(at 0 0 270)
			(layer "F.SilkS")
			(hide yes)
			(effects
				(font
					(size 1.27 1.27)
				)
			)
		)
		(property "Value" "4K7R2F-GP"
			(at 0.064008 -3.993896 270)
			(unlocked yes)
			(layer "F.Fab")
			(hide yes)
			(effects
				(font
					(size 1.016 1.016)
					(thickness 0.1524)
				)
			)
		)
		(property "Device Type" "R402H16"
			(at 0.064008 -5.517896 270)
			(unlocked yes)
			(layer "F.Fab")
			(hide yes)
			(effects
				(font
					(size 1.016 1.016)
					(thickness 0.1524)
				)
			)
		)
		(duplicate_pad_numbers_are_jumpers no)
		(fp_line
			(start -0.508 -0.9398)
			(end -0.508 0.9398)
			(stroke
				(width 0.1524)
				(type default)
			)
			(layer "F.SilkS")
		)
		(fp_line
			(start 0.508 -0.9398)
			(end -0.508 -0.9398)
			(stroke
				(width 0.1524)
				(type default)
			)
			(layer "F.SilkS")
		)
		(fp_rect
			(start -0.508 0.9398)
			(end 0.508 -0.9398)
			(stroke
				(width 0)
				(type default)
			)
			(fill no)
			(layer "F.CrtYd")
		)
		(fp_rect
			(start -0.508 0.9398)
			(end 0.508 -0.9398)
			(stroke
				(width 0)
				(type default)
			)
			(fill no)
			(layer "F.Fab")
		)
		(pad "1" smd custom
			(at 0 -0.4445 270)
			(size 0.1397 0.1397)
			(layers "F.Cu" "F.Mask" "F.Paste")
			(net "P1V8_E")
			(options
				(clearance outline)
				(anchor circle)
			)
			(primitives
				(gr_poly
					(pts
						(arc
							(start -0.1778 -0.2794)
							(mid -0.249642 -0.249642)
							(end -0.2794 -0.1778)
						)
						(arc
							(start -0.2794 0.1778)
							(mid -0.249642 0.249642)
							(end -0.1778 0.2794)
						)
						(arc
							(start 0.1778 0.2794)
							(mid 0.249642 0.249642)
							(end 0.2794 0.1778)
						)
						(arc
							(start 0.2794 -0.1778)
							(mid 0.249642 -0.249642)
							(end 0.1778 -0.2794)
						)
					)
					(width 0)
					(fill yes)
				)
			)
		)
		(pad "2" smd custom
			(at 0 0.4445 270)
			(size 0.1397 0.1397)
			(layers "F.Cu" "F.Mask" "F.Paste")
			(net "EXP_EEPROM_A0")
			(options
				(clearance outline)
				(anchor circle)
			)
			(primitives
				(gr_poly
					(pts
						(arc
							(start -0.1778 -0.2794)
							(mid -0.249642 -0.249642)
							(end -0.2794 -0.1778)
						)
						(arc
							(start -0.2794 0.1778)
							(mid -0.249642 0.249642)
							(end -0.1778 0.2794)
						)
						(arc
							(start 0.1778 0.2794)
							(mid 0.249642 0.249642)
							(end 0.2794 0.1778)
						)
						(arc
							(start 0.2794 -0.1778)
							(mid 0.249642 -0.249642)
							(end 0.1778 -0.2794)
						)
					)
					(width 0)
					(fill yes)
				)
			)
		)
	)
	(footprint ""
		(layer "F.Cu")
		(at 103.378 -236.855)
		(property "Reference" "SU18"
			(at 0 0 0)
			(layer "F.SilkS")
			(hide yes)
			(effects
				(font
					(size 1.27 1.27)
				)
			)
		)
		(property "Value" "PI3C3861-AQE-GP"
			(at 0 -13.1572 0)
			(unlocked yes)
			(layer "F.Fab")
			(hide yes)
			(effects
				(font
					(size 1.016 1.016)
					(thickness 0.1524)
				)
			)
		)
		(property "Device Type" "QSOIC24H69"
			(at 0 -15.1892 0)
			(unlocked yes)
			(layer "F.Fab")
			(hide yes)
			(effects
				(font
					(size 1.016 1.016)
					(thickness 0.1524)
				)
			)
		)
		(duplicate_pad_numbers_are_jumpers no)
		(fp_line
			(start -4.4958 -1.5748)
			(end 3.5814 -1.5748)
			(stroke
				(width 0.1524)
				(type default)
			)
			(layer "F.SilkS")
		)
		(fp_line
			(start -4.4958 -0.4318)
			(end -4.4958 -1.5748)
			(stroke
				(width 0.1524)
				(type default)
			)
			(layer "F.SilkS")
		)
		(fp_line
			(start -4.4958 -0.4318)
			(end -4.064 0)
			(stroke
				(width 0.1524)
				(type default)
			)
			(layer "F.SilkS")
		)
		(fp_line
			(start -4.4958 0.4318)
			(end -4.4958 -0.4318)
			(stroke
				(width 0.1524)
				(type default)
			)
			(layer "F.SilkS")
		)
		(fp_line
			(start -4.4958 0.4318)
			(end -4.4958 1.5748)
			(stroke
				(width 0.1524)
				(type default)
			)
			(layer "F.SilkS")
		)
		(fp_line
			(start -4.318 1.5748)
			(end -4.318 3.556)
			(stroke
				(width 0.508)
				(type default)
			)
			(layer "F.SilkS")
		)
		(fp_line
			(start -4.064 0)
			(end -4.4958 0.4318)
			(stroke
				(width 0.1524)
				(type default)
			)
			(layer "F.SilkS")
		)
		(fp_line
			(start 3.5814 -1.5748)
			(end 3.5814 1.5748)
			(stroke
				(width 0.1524)
				(type default)
			)
			(layer "F.SilkS")
		)
		(fp_line
			(start 3.5814 1.5748)
			(end -4.4958 1.5748)
			(stroke
				(width 0.1524)
				(type default)
			)
			(layer "F.SilkS")
		)
		(fp_line
			(start 3.5814 1.5748)
			(end 3.5814 -1.5748)
			(stroke
				(width 0.1524)
				(type default)
			)
			(layer "F.SilkS")
		)
		(fp_poly
			(pts
				(xy -3.683 -1.5748) (xy 3.5814 -1.5748) (xy 3.5814 1.5748) (xy -3.683 1.5748)
			)
			(stroke
				(width 0)
				(type default)
			)
			(fill yes)
			(layer "F.SilkS")
		)
		(fp_rect
			(start -4.572 3.81)
			(end 4.572 -3.81)
			(stroke
				(width 0)
				(type default)
			)
			(fill no)
			(layer "F.CrtYd")
		)
		(fp_poly
			(pts
				(xy -4.572 -3.81) (xy 4.572 -3.81) (xy 4.572 3.81) (xy -4.572 3.81)
			)
			(stroke
				(width 0)
				(type default)
			)
			(fill no)
			(layer "F.Fab")
		)
		(pad "1" smd rect
			(at -3.4925 2.6162)
			(size 0.3556 1.524)
			(layers "F.Cu" "F.Mask" "F.Paste")
			(net "Net_163")
		)
		(pad "2" smd rect
			(at -2.8575 2.6162)
			(size 0.3556 1.524)
			(layers "F.Cu" "F.Mask" "F.Paste")
			(net "SAS_HDD_LED_0")
		)
		(pad "3" smd rect
			(at -2.2225 2.6162)
			(size 0.3556 1.524)
			(layers "F.Cu" "F.Mask" "F.Paste")
			(net "SAS_HDD_LED_1")
		)
		(pad "4" smd rect
			(at -1.5875 2.6162)
			(size 0.3556 1.524)
			(layers "F.Cu" "F.Mask" "F.Paste")
			(net "SAS_HDD_LED_2")
		)
		(pad "5" smd rect
			(at -0.9525 2.6162)
			(size 0.3556 1.524)
			(layers "F.Cu" "F.Mask" "F.Paste")
			(net "SAS_HDD_LED_3")
		)
		(pad "6" smd rect
			(at -0.3175 2.6162)
			(size 0.3556 1.524)
			(layers "F.Cu" "F.Mask" "F.Paste")
			(net "SAS_HDD_LED_4")
		)
		(pad "7" smd rect
			(at 0.3175 2.6162)
			(size 0.3556 1.524)
			(layers "F.Cu" "F.Mask" "F.Paste")
			(net "SAS_HDD_LED_5")
		)
		(pad "8" smd rect
			(at 0.9525 2.6162)
			(size 0.3556 1.524)
			(layers "F.Cu" "F.Mask" "F.Paste")
			(net "SAS_HDD_LED_6")
		)
		(pad "9" smd rect
			(at 1.5875 2.6162)
			(size 0.3556 1.524)
			(layers "F.Cu" "F.Mask" "F.Paste")
			(net "SAS_HDD_LED_7")
		)
		(pad "10" smd rect
			(at 2.2225 2.6162)
			(size 0.3556 1.524)
			(layers "F.Cu" "F.Mask" "F.Paste")
			(net "SAS_HDD_LED_8")
		)
		(pad "11" smd rect
			(at 2.8575 2.6162)
			(size 0.3556 1.524)
			(layers "F.Cu" "F.Mask" "F.Paste")
			(net "SAS_HDD_LED_9")
		)
		(pad "12" smd rect
			(at 3.4925 2.6162)
			(size 0.3556 1.524)
			(layers "F.Cu" "F.Mask" "F.Paste")
			(net "GND")
		)
		(pad "13" smd rect
			(at 3.4925 -2.6162)
			(size 0.3556 1.524)
			(layers "F.Cu" "F.Mask" "F.Paste")
			(net "SAS_FAULT_LED9")
		)
		(pad "14" smd rect
			(at 2.8575 -2.6162)
			(size 0.3556 1.524)
			(layers "F.Cu" "F.Mask" "F.Paste")
			(net "SAS_FAULT_LED8")
		)
		(pad "15" smd rect
			(at 2.2225 -2.6162)
			(size 0.3556 1.524)
			(layers "F.Cu" "F.Mask" "F.Paste")
			(net "SAS_FAULT_LED7")
		)
		(pad "16" smd rect
			(at 1.5875 -2.6162)
			(size 0.3556 1.524)
			(layers "F.Cu" "F.Mask" "F.Paste")
			(net "SAS_FAULT_LED6")
		)
		(pad "17" smd rect
			(at 0.9525 -2.6162)
			(size 0.3556 1.524)
			(layers "F.Cu" "F.Mask" "F.Paste")
			(net "SAS_FAULT_LED5")
		)
		(pad "18" smd rect
			(at 0.3175 -2.6162)
			(size 0.3556 1.524)
			(layers "F.Cu" "F.Mask" "F.Paste")
			(net "SAS_FAULT_LED4")
		)
		(pad "19" smd rect
			(at -0.3175 -2.6162)
			(size 0.3556 1.524)
			(layers "F.Cu" "F.Mask" "F.Paste")
			(net "SAS_FAULT_LED3")
		)
		(pad "20" smd rect
			(at -0.9525 -2.6162)
			(size 0.3556 1.524)
			(layers "F.Cu" "F.Mask" "F.Paste")
			(net "SAS_FAULT_LED2")
		)
		(pad "21" smd rect
			(at -1.5875 -2.6162)
			(size 0.3556 1.524)
			(layers "F.Cu" "F.Mask" "F.Paste")
			(net "SAS_FAULT_LED1")
		)
		(pad "22" smd rect
			(at -2.2225 -2.6162)
			(size 0.3556 1.524)
			(layers "F.Cu" "F.Mask" "F.Paste")
			(net "SAS_FAULT_LED0")
		)
		(pad "23" smd rect
			(at -2.8575 -2.6162)
			(size 0.3556 1.524)
			(layers "F.Cu" "F.Mask" "F.Paste")
			(net "PCIE_MATED#_LED_CD")
		)
		(pad "24" smd rect
			(at -3.4925 -2.6162)
			(size 0.3556 1.524)
			(layers "F.Cu" "F.Mask" "F.Paste")
			(net "P3V3_STBY")
		)
	)
	(footprint ""
		(layer "F.Cu")
		(at 308.936136 -109.863128 -90)
		(property "Reference" "PR34"
			(at 0 0 270)
			(layer "F.SilkS")
			(hide yes)
			(effects
				(font
					(size 1.27 1.27)
				)
			)
		)
		(property "Value" "0R2J-2-GP"
			(at 0.064008 -3.993896 270)
			(unlocked yes)
			(layer "F.Fab")
			(hide yes)
			(effects
				(font
					(size 1.016 1.016)
					(thickness 0.1524)
				)
			)
		)
		(property "Device Type" "R402H16"
			(at 0.064008 -5.517896 270)
			(unlocked yes)
			(layer "F.Fab")
			(hide yes)
			(effects
				(font
					(size 1.016 1.016)
					(thickness 0.1524)
				)
			)
		)
		(duplicate_pad_numbers_are_jumpers no)
		(fp_line
			(start -0.508 -0.9398)
			(end -0.508 0.9398)
			(stroke
				(width 0.1524)
				(type default)
			)
			(layer "F.SilkS")
		)
		(fp_line
			(start 0.508 -0.9398)
			(end -0.508 -0.9398)
			(stroke
				(width 0.1524)
				(type default)
			)
			(layer "F.SilkS")
		)
		(fp_rect
			(start -0.508 0.9398)
			(end 0.508 -0.9398)
			(stroke
				(width 0)
				(type default)
			)
			(fill no)
			(layer "F.CrtYd")
		)
		(fp_rect
			(start -0.508 0.9398)
			(end 0.508 -0.9398)
			(stroke
				(width 0)
				(type default)
			)
			(fill no)
			(layer "F.Fab")
		)
		(pad "1" smd custom
			(at 0 -0.4445 270)
			(size 0.1397 0.1397)
			(layers "F.Cu" "F.Mask" "F.Paste")
			(net "P3V3_STBY_ROVP")
			(options
				(clearance outline)
				(anchor circle)
			)
			(primitives
				(gr_poly
					(pts
						(arc
							(start -0.1778 -0.2794)
							(mid -0.249642 -0.249642)
							(end -0.2794 -0.1778)
						)
						(arc
							(start -0.2794 0.1778)
							(mid -0.249642 0.249642)
							(end -0.1778 0.2794)
						)
						(arc
							(start 0.1778 0.2794)
							(mid 0.249642 0.249642)
							(end 0.2794 0.1778)
						)
						(arc
							(start 0.2794 -0.1778)
							(mid 0.249642 -0.249642)
							(end 0.1778 -0.2794)
						)
					)
					(width 0)
					(fill yes)
				)
			)
		)
		(pad "2" smd custom
			(at 0 0.4445 270)
			(size 0.1397 0.1397)
			(layers "F.Cu" "F.Mask" "F.Paste")
			(net "P3V3_STBY")
			(options
				(clearance outline)
				(anchor circle)
			)
			(primitives
				(gr_poly
					(pts
						(arc
							(start -0.1778 -0.2794)
							(mid -0.249642 -0.249642)
							(end -0.2794 -0.1778)
						)
						(arc
							(start -0.2794 0.1778)
							(mid -0.249642 0.249642)
							(end -0.1778 0.2794)
						)
						(arc
							(start 0.1778 0.2794)
							(mid 0.249642 0.249642)
							(end 0.2794 0.1778)
						)
						(arc
							(start 0.2794 -0.1778)
							(mid 0.249642 -0.249642)
							(end 0.1778 -0.2794)
						)
					)
					(width 0)
					(fill yes)
				)
			)
		)
	)
	(footprint ""
		(layer "F.Cu")
		(at 218.059 -110.363 180)
		(property "Reference" "PC149"
			(at 0 0 180)
			(layer "F.SilkS")
			(hide yes)
			(effects
				(font
					(size 1.27 1.27)
				)
			)
		)
		(property "Value" "SCD1U16V2KX-3GP"
			(at 1.1811 -2.7051 180)
			(unlocked yes)
			(layer "F.Fab")
			(hide yes)
			(effects
				(font
					(size 1.016 1.016)
					(thickness 0.1524)
				)
			)
		)
		(property "Device Type" "C402H22"
			(at 1.1811 -4.2291 180)
			(unlocked yes)
			(layer "F.Fab")
			(hide yes)
			(effects
				(font
					(size 1.016 1.016)
					(thickness 0.1524)
				)
			)
		)
		(duplicate_pad_numbers_are_jumpers no)
		(fp_rect
			(start -0.4318 0.9525)
			(end 0.4318 -0.9525)
			(stroke
				(width 0)
				(type default)
			)
			(fill no)
			(layer "F.CrtYd")
		)
		(fp_rect
			(start -0.4318 0.9525)
			(end 0.4318 -0.9525)
			(stroke
				(width 0)
				(type default)
			)
			(fill no)
			(layer "F.Fab")
		)
		(pad "1" smd custom
			(at 0 -0.4445 180)
			(size 0.1524 0.1524)
			(layers "F.Cu" "F.Mask" "F.Paste")
			(net "TPS74801_1V5_C_EN")
			(options
				(clearance outline)
				(anchor circle)
			)
			(primitives
				(gr_poly
					(pts
						(arc
							(start 0.3048 -0.2032)
							(mid 0.275042 -0.275042)
							(end 0.2032 -0.3048)
						)
						(arc
							(start -0.2032 -0.3048)
							(mid -0.275042 -0.275042)
							(end -0.3048 -0.2032)
						)
						(arc
							(start -0.3048 0.2032)
							(mid -0.275042 0.275042)
							(end -0.2032 0.3048)
						)
						(arc
							(start 0.2032 0.3048)
							(mid 0.275042 0.275042)
							(end 0.3048 0.2032)
						)
					)
					(width 0)
					(fill yes)
				)
			)
		)
		(pad "2" smd custom
			(at 0 0.4445 180)
			(size 0.1524 0.1524)
			(layers "F.Cu" "F.Mask" "F.Paste")
			(net "GND")
			(options
				(clearance outline)
				(anchor circle)
			)
			(primitives
				(gr_poly
					(pts
						(arc
							(start 0.3048 -0.2032)
							(mid 0.275042 -0.275042)
							(end 0.2032 -0.3048)
						)
						(arc
							(start -0.2032 -0.3048)
							(mid -0.275042 -0.275042)
							(end -0.3048 -0.2032)
						)
						(arc
							(start -0.3048 0.2032)
							(mid -0.275042 0.275042)
							(end -0.2032 0.3048)
						)
						(arc
							(start 0.2032 0.3048)
							(mid 0.275042 0.275042)
							(end 0.3048 0.2032)
						)
					)
					(width 0)
					(fill yes)
				)
			)
		)
	)
)
